(kicad_pcb
	(version 20260206)
	(generator "pcbnew")
	(generator_version "10.0")
	(general
		(thickness 1.6)
		(legacy_teardrops no)
	)
	(paper "A4")
	(title_block
		(title "04192023_DAF0TMB3IC0_F0TG_MB_C_brd_V02_OCP.brd")
		(comment 1 "Grand Teton / footprints 7908-7914 of 8354")
	)
	(layers
		(0 "F.Cu" signal "TOP")
		(4 "In1.Cu" signal "GND")
		(6 "In2.Cu" signal "IN1")
		(8 "In3.Cu" signal "GND1")
		(10 "In4.Cu" signal "IN2")
		(12 "In5.Cu" signal "GND2")
		(14 "In6.Cu" signal "IN3")
		(16 "In7.Cu" signal "GND3")
		(18 "In8.Cu" signal "VCC")
		(20 "In9.Cu" signal "VCC1")
		(22 "In10.Cu" signal "GND4")
		(24 "In11.Cu" signal "IN4")
		(26 "In12.Cu" signal "GND5")
		(28 "In13.Cu" signal "IN5")
		(30 "In14.Cu" signal "GND6")
		(32 "In15.Cu" signal "IN6")
		(34 "In16.Cu" signal "GND7")
		(2 "B.Cu" signal "BOTTOM")
		(9 "F.Adhes" user "F.Adhesive")
		(11 "B.Adhes" user "B.Adhesive")
		(13 "F.Paste" user "Package Geometry/Pastemask Top")
		(15 "B.Paste" user "Package Geometry/Pastemask Bottom")
		(5 "F.SilkS" user "Ref Des/Silkscreen Top")
		(7 "B.SilkS" user "Ref Des/Silkscreen Bottom")
		(1 "F.Mask" user "Board Geometry/Soldermask Top")
		(3 "B.Mask" user "Board Geometry/Soldermask Bottom")
		(17 "Dwgs.User" user "User.Drawings")
		(19 "Cmts.User" user "User.Comments")
		(21 "Eco1.User" user "User.Eco1")
		(23 "Eco2.User" user "User.Eco2")
		(25 "Edge.Cuts" user "Board Geometry/Outline")
		(27 "Margin" user)
		(31 "F.CrtYd" user "Package Geometry/Place Bound Top")
		(29 "B.CrtYd" user "Package Geometry/Place Bound Bottom")
		(35 "F.Fab" user "Ref Des/Assembly Top")
		(33 "B.Fab" user "Ref Des/Assembly Bottom")
	)
	(footprint ""
		(layer "B.Cu")
		(at 398.502124 -344.850212 -90)
		(property "Reference" "R6100"
			(at 0 0 90)
			(layer "B.SilkS")
			(hide yes)
			(effects
				(font
					(size 1.27 1.27)
				)
				(justify mirror)
			)
		)
		(property "Value" ""
			(at 0 0 90)
			(layer "B.Fab")
			(effects
				(font
					(size 1.27 1.27)
				)
				(justify mirror)
			)
		)
		(duplicate_pad_numbers_are_jumpers no)
		(fp_line
			(start -0.7874 0.4064)
			(end 0.7874 0.4064)
			(stroke
				(width 0.1524)
				(type default)
			)
			(layer "B.SilkS")
		)
		(fp_line
			(start 0.7874 0.4064)
			(end 0.7874 -0.4064)
			(stroke
				(width 0.1524)
				(type default)
			)
			(layer "B.SilkS")
		)
		(fp_line
			(start -0.7874 -0.4064)
			(end -0.7874 0.4064)
			(stroke
				(width 0.1524)
				(type default)
			)
			(layer "B.SilkS")
		)
		(fp_line
			(start 0.7874 -0.4064)
			(end -0.7874 -0.4064)
			(stroke
				(width 0.1524)
				(type default)
			)
			(layer "B.SilkS")
		)
		(fp_line
			(start -0.67945 0.3048)
			(end -0.120396 0.3048)
			(stroke
				(width 0.1)
				(type default)
			)
			(layer "B.Fab")
		)
		(fp_line
			(start -0.120396 0.3048)
			(end -0.120396 0.2794)
			(stroke
				(width 0.1)
				(type default)
			)
			(layer "B.Fab")
		)
		(fp_line
			(start 0.12065 0.3048)
			(end 0.67945 0.3048)
			(stroke
				(width 0.1)
				(type default)
			)
			(layer "B.Fab")
		)
		(fp_line
			(start 0.67945 0.3048)
			(end 0.67945 -0.305054)
			(stroke
				(width 0.1)
				(type default)
			)
			(layer "B.Fab")
		)
		(fp_line
			(start -0.120396 0.2794)
			(end 0.12065 0.2794)
			(stroke
				(width 0.1)
				(type default)
			)
			(layer "B.Fab")
		)
		(fp_line
			(start 0.12065 0.2794)
			(end 0.12065 0.3048)
			(stroke
				(width 0.1)
				(type default)
			)
			(layer "B.Fab")
		)
		(fp_line
			(start -0.12065 -0.2794)
			(end -0.12065 -0.3048)
			(stroke
				(width 0.1)
				(type default)
			)
			(layer "B.Fab")
		)
		(fp_line
			(start 0.12065 -0.2794)
			(end -0.12065 -0.2794)
			(stroke
				(width 0.1)
				(type default)
			)
			(layer "B.Fab")
		)
		(fp_line
			(start -0.67945 -0.3048)
			(end -0.67945 0.3048)
			(stroke
				(width 0.1)
				(type default)
			)
			(layer "B.Fab")
		)
		(fp_line
			(start -0.12065 -0.3048)
			(end -0.67945 -0.3048)
			(stroke
				(width 0.1)
				(type default)
			)
			(layer "B.Fab")
		)
		(fp_line
			(start 0.12065 -0.305054)
			(end 0.12065 -0.2794)
			(stroke
				(width 0.1)
				(type default)
			)
			(layer "B.Fab")
		)
		(fp_line
			(start 0.67945 -0.305054)
			(end 0.12065 -0.305054)
			(stroke
				(width 0.1)
				(type default)
			)
			(layer "B.Fab")
		)
		(pad "1" smd circle
			(at 0.40005 0 90)
			(size 0 0)
			(layers "B.Cu" "B.Mask" "B.Paste")
			(net "FM_BIOS_POST_CMPLT_BUF_R1_N")
		)
		(pad "2" smd circle
			(at -0.40005 0 90)
			(size 0 0)
			(layers "B.Cu" "B.Mask" "B.Paste")
			(net "FM_BIOS_POST_CMPLT_BUF_N")
		)
	)
	(footprint ""
		(layer "B.Cu")
		(at 397.876014 -183.888888 90)
		(property "Reference" "PC601"
			(at 6.967728 0.110998 270)
			(unlocked yes)
			(layer "B.SilkS")
			(effects
				(font
					(size 0.7874 0.5842)
					(thickness 0.1524)
				)
				(justify left mirror)
			)
		)
		(property "Value" ""
			(at 0 0 90)
			(layer "B.Fab")
			(effects
				(font
					(size 1.27 1.27)
				)
				(justify mirror)
			)
		)
		(duplicate_pad_numbers_are_jumpers no)
		(fp_line
			(start 4.533392 -2.249932)
			(end -4.533392 -2.249932)
			(stroke
				(width 0.1524)
				(type default)
			)
			(layer "B.SilkS")
		)
		(fp_line
			(start -4.533392 -2.249932)
			(end -4.533392 2.249932)
			(stroke
				(width 0.1524)
				(type default)
			)
			(layer "B.SilkS")
		)
		(fp_line
			(start 4.533392 2.249932)
			(end 4.533392 -2.249932)
			(stroke
				(width 0.1524)
				(type default)
			)
			(layer "B.SilkS")
		)
		(fp_line
			(start -4.533392 2.249932)
			(end 4.533392 2.249932)
			(stroke
				(width 0.1524)
				(type default)
			)
			(layer "B.SilkS")
		)
		(fp_rect
			(start 4.533392 -2.326132)
			(end 5.39242 2.326132)
			(stroke
				(width 0)
				(type default)
			)
			(fill yes)
			(layer "B.SilkS")
		)
		(fp_line
			(start 3.750056 -2.249932)
			(end -3.750056 -2.249932)
			(stroke
				(width 0.1)
				(type default)
			)
			(layer "B.Fab")
		)
		(fp_line
			(start -3.750056 -2.249932)
			(end -3.750056 2.249932)
			(stroke
				(width 0.1)
				(type default)
			)
			(layer "B.Fab")
		)
		(fp_line
			(start 3.750056 2.249932)
			(end 3.750056 -2.249932)
			(stroke
				(width 0.1)
				(type default)
			)
			(layer "B.Fab")
		)
		(fp_line
			(start -3.750056 2.249932)
			(end 3.750056 2.249932)
			(stroke
				(width 0.1)
				(type default)
			)
			(layer "B.Fab")
		)
		(fp_text user "-"
			(at -4.8514 -0.14605 90)
			(unlocked yes)
			(layer "B.SilkS")
			(effects
				(font
					(size 1.905 1.4224)
					(thickness 0.1524)
				)
				(justify left mirror)
			)
		)
		(fp_text user "+"
			(at 6.322314 0.786384 0)
			(unlocked yes)
			(layer "B.SilkS")
			(effects
				(font
					(size 1.905 1.4224)
					(thickness 0.1524)
				)
				(justify left mirror)
			)
		)
		(fp_text user "-"
			(at -4.8514 -0.14605 90)
			(unlocked yes)
			(layer "B.Fab")
			(effects
				(font
					(size 1.905 1.4224)
					(thickness 0.1524)
				)
				(justify left mirror)
			)
		)
		(fp_text user "+"
			(at 6.322314 0.786384 0)
			(unlocked yes)
			(layer "B.Fab")
			(effects
				(font
					(size 1.905 1.4224)
					(thickness 0.1524)
				)
				(justify left mirror)
			)
		)
		(pad "1" smd rect
			(at 3.199892 0 270)
			(size 2.413 2.8194)
			(layers "B.Cu" "B.Mask" "B.Paste")
			(net "PVDDCR_SOC_P0")
		)
		(pad "2" smd rect
			(at -3.199892 0 270)
			(size 2.413 2.8194)
			(layers "B.Cu" "B.Mask" "B.Paste")
			(net "GND")
		)
	)
	(footprint ""
		(layer "B.Cu")
		(at 370.272818 -393.88288 -90)
		(property "Reference" "C1006"
			(at 0 0 90)
			(layer "B.SilkS")
			(hide yes)
			(effects
				(font
					(size 1.27 1.27)
				)
				(justify mirror)
			)
		)
		(property "Value" ""
			(at 0 0 90)
			(layer "B.Fab")
			(effects
				(font
					(size 1.27 1.27)
				)
				(justify mirror)
			)
		)
		(duplicate_pad_numbers_are_jumpers no)
		(fp_line
			(start -0.299974 0.150114)
			(end 0.299974 0.150114)
			(stroke
				(width 0.1)
				(type default)
			)
			(layer "B.Fab")
		)
		(fp_line
			(start 0.299974 0.150114)
			(end 0.299974 -0.150114)
			(stroke
				(width 0.1)
				(type default)
			)
			(layer "B.Fab")
		)
		(fp_line
			(start -0.299974 -0.150114)
			(end -0.299974 0.150114)
			(stroke
				(width 0.1)
				(type default)
			)
			(layer "B.Fab")
		)
		(fp_line
			(start 0.299974 -0.150114)
			(end -0.299974 -0.150114)
			(stroke
				(width 0.1)
				(type default)
			)
			(layer "B.Fab")
		)
		(pad "1" smd rect
			(at 0.2667 0 90)
			(size 0.3048 0.381)
			(layers "B.Cu" "B.Mask" "B.Paste")
			(net "P0V9_CPU0_RT3_2A")
		)
		(pad "2" smd rect
			(at -0.2667 0 90)
			(size 0.3048 0.381)
			(layers "B.Cu" "B.Mask" "B.Paste")
			(net "GND")
		)
	)
	(footprint ""
		(layer "B.Cu")
		(at 190.404496 -194.8942 180)
		(property "Reference" "R1589"
			(at 0 0 0)
			(layer "B.SilkS")
			(hide yes)
			(effects
				(font
					(size 1.27 1.27)
				)
				(justify mirror)
			)
		)
		(property "Value" ""
			(at 0 0 0)
			(layer "B.Fab")
			(effects
				(font
					(size 1.27 1.27)
				)
				(justify mirror)
			)
		)
		(duplicate_pad_numbers_are_jumpers no)
		(fp_line
			(start 0.7874 0.4064)
			(end 0.7874 -0.4064)
			(stroke
				(width 0.1524)
				(type default)
			)
			(layer "B.SilkS")
		)
		(fp_line
			(start 0.7874 -0.4064)
			(end -0.7874 -0.4064)
			(stroke
				(width 0.1524)
				(type default)
			)
			(layer "B.SilkS")
		)
		(fp_line
			(start -0.7874 0.4064)
			(end 0.7874 0.4064)
			(stroke
				(width 0.1524)
				(type default)
			)
			(layer "B.SilkS")
		)
		(fp_line
			(start -0.7874 -0.4064)
			(end -0.7874 0.4064)
			(stroke
				(width 0.1524)
				(type default)
			)
			(layer "B.SilkS")
		)
		(fp_line
			(start 0.67945 0.3048)
			(end 0.67945 -0.305054)
			(stroke
				(width 0.1)
				(type default)
			)
			(layer "B.Fab")
		)
		(fp_line
			(start 0.67945 -0.305054)
			(end 0.12065 -0.305054)
			(stroke
				(width 0.1)
				(type default)
			)
			(layer "B.Fab")
		)
		(fp_line
			(start 0.12065 0.3048)
			(end 0.67945 0.3048)
			(stroke
				(width 0.1)
				(type default)
			)
			(layer "B.Fab")
		)
		(fp_line
			(start 0.12065 0.2794)
			(end 0.12065 0.3048)
			(stroke
				(width 0.1)
				(type default)
			)
			(layer "B.Fab")
		)
		(fp_line
			(start 0.12065 -0.2794)
			(end -0.12065 -0.2794)
			(stroke
				(width 0.1)
				(type default)
			)
			(layer "B.Fab")
		)
		(fp_line
			(start 0.12065 -0.305054)
			(end 0.12065 -0.2794)
			(stroke
				(width 0.1)
				(type default)
			)
			(layer "B.Fab")
		)
		(fp_line
			(start -0.120396 0.3048)
			(end -0.120396 0.2794)
			(stroke
				(width 0.1)
				(type default)
			)
			(layer "B.Fab")
		)
		(fp_line
			(start -0.120396 0.2794)
			(end 0.12065 0.2794)
			(stroke
				(width 0.1)
				(type default)
			)
			(layer "B.Fab")
		)
		(fp_line
			(start -0.12065 -0.2794)
			(end -0.12065 -0.3048)
			(stroke
				(width 0.1)
				(type default)
			)
			(layer "B.Fab")
		)
		(fp_line
			(start -0.12065 -0.3048)
			(end -0.67945 -0.3048)
			(stroke
				(width 0.1)
				(type default)
			)
			(layer "B.Fab")
		)
		(fp_line
			(start -0.67945 0.3048)
			(end -0.120396 0.3048)
			(stroke
				(width 0.1)
				(type default)
			)
			(layer "B.Fab")
		)
		(fp_line
			(start -0.67945 -0.3048)
			(end -0.67945 0.3048)
			(stroke
				(width 0.1)
				(type default)
			)
			(layer "B.Fab")
		)
		(pad "1" smd circle
			(at 0.40005 0)
			(size 0 0)
			(layers "B.Cu" "B.Mask" "B.Paste")
			(net "I3C_SPD_DDRGL_CPU1_SCL")
		)
		(pad "2" smd circle
			(at -0.40005 0)
			(size 0 0)
			(layers "B.Cu" "B.Mask" "B.Paste")
			(net "I3C_SPD_DDRJ_CPU1_SCL")
		)
	)
	(footprint ""
		(layer "B.Cu")
		(at 173.583092 -418.7571 -90)
		(property "Reference" "R2801"
			(at 0 0 90)
			(layer "B.SilkS")
			(hide yes)
			(effects
				(font
					(size 1.27 1.27)
				)
				(justify mirror)
			)
		)
		(property "Value" ""
			(at 0 0 90)
			(layer "B.Fab")
			(effects
				(font
					(size 1.27 1.27)
				)
				(justify mirror)
			)
		)
		(duplicate_pad_numbers_are_jumpers no)
		(fp_line
			(start -0.7874 0.4064)
			(end 0.7874 0.4064)
			(stroke
				(width 0.1524)
				(type default)
			)
			(layer "B.SilkS")
		)
		(fp_line
			(start 0.7874 0.4064)
			(end 0.7874 -0.4064)
			(stroke
				(width 0.1524)
				(type default)
			)
			(layer "B.SilkS")
		)
		(fp_line
			(start -0.7874 -0.4064)
			(end -0.7874 0.4064)
			(stroke
				(width 0.1524)
				(type default)
			)
			(layer "B.SilkS")
		)
		(fp_line
			(start 0.7874 -0.4064)
			(end -0.7874 -0.4064)
			(stroke
				(width 0.1524)
				(type default)
			)
			(layer "B.SilkS")
		)
		(fp_line
			(start -0.67945 0.3048)
			(end -0.120396 0.3048)
			(stroke
				(width 0.1)
				(type default)
			)
			(layer "B.Fab")
		)
		(fp_line
			(start -0.120396 0.3048)
			(end -0.120396 0.2794)
			(stroke
				(width 0.1)
				(type default)
			)
			(layer "B.Fab")
		)
		(fp_line
			(start 0.12065 0.3048)
			(end 0.67945 0.3048)
			(stroke
				(width 0.1)
				(type default)
			)
			(layer "B.Fab")
		)
		(fp_line
			(start 0.67945 0.3048)
			(end 0.67945 -0.305054)
			(stroke
				(width 0.1)
				(type default)
			)
			(layer "B.Fab")
		)
		(fp_line
			(start -0.120396 0.2794)
			(end 0.12065 0.2794)
			(stroke
				(width 0.1)
				(type default)
			)
			(layer "B.Fab")
		)
		(fp_line
			(start 0.12065 0.2794)
			(end 0.12065 0.3048)
			(stroke
				(width 0.1)
				(type default)
			)
			(layer "B.Fab")
		)
		(fp_line
			(start -0.12065 -0.2794)
			(end -0.12065 -0.3048)
			(stroke
				(width 0.1)
				(type default)
			)
			(layer "B.Fab")
		)
		(fp_line
			(start 0.12065 -0.2794)
			(end -0.12065 -0.2794)
			(stroke
				(width 0.1)
				(type default)
			)
			(layer "B.Fab")
		)
		(fp_line
			(start -0.67945 -0.3048)
			(end -0.67945 0.3048)
			(stroke
				(width 0.1)
				(type default)
			)
			(layer "B.Fab")
		)
		(fp_line
			(start -0.12065 -0.3048)
			(end -0.67945 -0.3048)
			(stroke
				(width 0.1)
				(type default)
			)
			(layer "B.Fab")
		)
		(fp_line
			(start 0.12065 -0.305054)
			(end 0.12065 -0.2794)
			(stroke
				(width 0.1)
				(type default)
			)
			(layer "B.Fab")
		)
		(fp_line
			(start 0.67945 -0.305054)
			(end 0.12065 -0.305054)
			(stroke
				(width 0.1)
				(type default)
			)
			(layer "B.Fab")
		)
		(pad "1" smd circle
			(at 0.40005 0 90)
			(size 0 0)
			(layers "B.Cu" "B.Mask" "B.Paste")
			(net "SMB_FAN_3V3AUX_R_SDA")
		)
		(pad "2" smd circle
			(at -0.40005 0 90)
			(size 0 0)
			(layers "B.Cu" "B.Mask" "B.Paste")
			(net "SMB_FAN_3V3AUX_BUF_SDA")
		)
	)
	(footprint ""
		(layer "B.Cu")
		(at 453.432418 -193.99631)
		(property "Reference" "C112"
			(at 0 0 0)
			(layer "B.SilkS")
			(hide yes)
			(effects
				(font
					(size 1.27 1.27)
				)
				(justify mirror)
			)
		)
		(property "Value" ""
			(at 0 0 0)
			(layer "B.Fab")
			(effects
				(font
					(size 1.27 1.27)
				)
				(justify mirror)
			)
		)
		(duplicate_pad_numbers_are_jumpers no)
		(fp_line
			(start -0.7874 -0.4064)
			(end -0.7874 0.4064)
			(stroke
				(width 0.1524)
				(type default)
			)
			(layer "B.SilkS")
		)
		(fp_line
			(start -0.7874 0.4064)
			(end 0.7874 0.4064)
			(stroke
				(width 0.1524)
				(type default)
			)
			(layer "B.SilkS")
		)
		(fp_line
			(start 0.7874 -0.4064)
			(end -0.7874 -0.4064)
			(stroke
				(width 0.1524)
				(type default)
			)
			(layer "B.SilkS")
		)
		(fp_line
			(start 0.7874 0.4064)
			(end 0.7874 -0.4064)
			(stroke
				(width 0.1524)
				(type default)
			)
			(layer "B.SilkS")
		)
		(fp_line
			(start -0.67945 -0.3048)
			(end -0.67945 0.3048)
			(stroke
				(width 0.1)
				(type default)
			)
			(layer "B.Fab")
		)
		(fp_line
			(start -0.67945 0.3048)
			(end -0.120396 0.3048)
			(stroke
				(width 0.1)
				(type default)
			)
			(layer "B.Fab")
		)
		(fp_line
			(start -0.12065 -0.3048)
			(end -0.67945 -0.3048)
			(stroke
				(width 0.1)
				(type default)
			)
			(layer "B.Fab")
		)
		(fp_line
			(start -0.12065 -0.2794)
			(end -0.12065 -0.3048)
			(stroke
				(width 0.1)
				(type default)
			)
			(layer "B.Fab")
		)
		(fp_line
			(start -0.120396 0.2794)
			(end 0.12065 0.2794)
			(stroke
				(width 0.1)
				(type default)
			)
			(layer "B.Fab")
		)
		(fp_line
			(start -0.120396 0.3048)
			(end -0.120396 0.2794)
			(stroke
				(width 0.1)
				(type default)
			)
			(layer "B.Fab")
		)
		(fp_line
			(start 0.12065 -0.305054)
			(end 0.12065 -0.2794)
			(stroke
				(width 0.1)
				(type default)
			)
			(layer "B.Fab")
		)
		(fp_line
			(start 0.12065 -0.2794)
			(end -0.12065 -0.2794)
			(stroke
				(width 0.1)
				(type default)
			)
			(layer "B.Fab")
		)
		(fp_line
			(start 0.12065 0.2794)
			(end 0.12065 0.3048)
			(stroke
				(width 0.1)
				(type default)
			)
			(layer "B.Fab")
		)
		(fp_line
			(start 0.12065 0.3048)
			(end 0.67945 0.3048)
			(stroke
				(width 0.1)
				(type default)
			)
			(layer "B.Fab")
		)
		(fp_line
			(start 0.67945 -0.305054)
			(end 0.12065 -0.305054)
			(stroke
				(width 0.1)
				(type default)
			)
			(layer "B.Fab")
		)
		(fp_line
			(start 0.67945 0.3048)
			(end 0.67945 -0.305054)
			(stroke
				(width 0.1)
				(type default)
			)
			(layer "B.Fab")
		)
		(pad "1" smd circle
			(at 0.40005 0 180)
			(size 0 0)
			(layers "B.Cu" "B.Mask" "B.Paste")
			(net "P3V3_AUX")
		)
		(pad "2" smd circle
			(at -0.40005 0 180)
			(size 0 0)
			(layers "B.Cu" "B.Mask" "B.Paste")
			(net "GND")
		)
	)
	(footprint ""
		(layer "B.Cu")
		(at 365.709454 -266.00531)
		(property "Reference" "C2640"
			(at 0 0 0)
			(layer "B.SilkS")
			(hide yes)
			(effects
				(font
					(size 1.27 1.27)
				)
				(justify mirror)
			)
		)
		(property "Value" ""
			(at 0 0 0)
			(layer "B.Fab")
			(effects
				(font
					(size 1.27 1.27)
				)
				(justify mirror)
			)
		)
		(duplicate_pad_numbers_are_jumpers no)
		(fp_line
			(start -0.7874 -0.4064)
			(end -0.7874 0.4064)
			(stroke
				(width 0.1524)
				(type default)
			)
			(layer "B.SilkS")
		)
		(fp_line
			(start -0.7874 0.4064)
			(end 0.7874 0.4064)
			(stroke
				(width 0.1524)
				(type default)
			)
			(layer "B.SilkS")
		)
		(fp_line
			(start 0.7874 -0.4064)
			(end -0.7874 -0.4064)
			(stroke
				(width 0.1524)
				(type default)
			)
			(layer "B.SilkS")
		)
		(fp_line
			(start 0.7874 0.4064)
			(end 0.7874 -0.4064)
			(stroke
				(width 0.1524)
				(type default)
			)
			(layer "B.SilkS")
		)
		(fp_line
			(start -0.67945 -0.3048)
			(end -0.67945 0.3048)
			(stroke
				(width 0.1)
				(type default)
			)
			(layer "B.Fab")
		)
		(fp_line
			(start -0.67945 0.3048)
			(end -0.120396 0.3048)
			(stroke
				(width 0.1)
				(type default)
			)
			(layer "B.Fab")
		)
		(fp_line
			(start -0.12065 -0.3048)
			(end -0.67945 -0.3048)
			(stroke
				(width 0.1)
				(type default)
			)
			(layer "B.Fab")
		)
		(fp_line
			(start -0.12065 -0.2794)
			(end -0.12065 -0.3048)
			(stroke
				(width 0.1)
				(type default)
			)
			(layer "B.Fab")
		)
		(fp_line
			(start -0.120396 0.2794)
			(end 0.12065 0.2794)
			(stroke
				(width 0.1)
				(type default)
			)
			(layer "B.Fab")
		)
		(fp_line
			(start -0.120396 0.3048)
			(end -0.120396 0.2794)
			(stroke
				(width 0.1)
				(type default)
			)
			(layer "B.Fab")
		)
		(fp_line
			(start 0.12065 -0.305054)
			(end 0.12065 -0.2794)
			(stroke
				(width 0.1)
				(type default)
			)
			(layer "B.Fab")
		)
		(fp_line
			(start 0.12065 -0.2794)
			(end -0.12065 -0.2794)
			(stroke
				(width 0.1)
				(type default)
			)
			(layer "B.Fab")
		)
		(fp_line
			(start 0.12065 0.2794)
			(end 0.12065 0.3048)
			(stroke
				(width 0.1)
				(type default)
			)
			(layer "B.Fab")
		)
		(fp_line
			(start 0.12065 0.3048)
			(end 0.67945 0.3048)
			(stroke
				(width 0.1)
				(type default)
			)
			(layer "B.Fab")
		)
		(fp_line
			(start 0.67945 -0.305054)
			(end 0.12065 -0.305054)
			(stroke
				(width 0.1)
				(type default)
			)
			(layer "B.Fab")
		)
		(fp_line
			(start 0.67945 0.3048)
			(end 0.67945 -0.305054)
			(stroke
				(width 0.1)
				(type default)
			)
			(layer "B.Fab")
		)
		(pad "1" smd circle
			(at 0.40005 0 180)
			(size 0 0)
			(layers "B.Cu" "B.Mask" "B.Paste")
			(net "PVDD11_S3_P0")
		)
		(pad "2" smd circle
			(at -0.40005 0 180)
			(size 0 0)
			(layers "B.Cu" "B.Mask" "B.Paste")
			(net "GND")
		)
	)
)
